# S9S_MB_2U (Grand Teton) — schematic netlist excerpt (pin names and nets, part order shuffled) for the footprints in the layout excerpt that follows; sources: Cadence DE-HDL packaged netlist, KiCad conversion of 03242023_DA0F0TMBIJ0_F0T_Motherboard_J_brd_V01_OCP.brd

PR154  Q_RES  0 5% CHIP  pkg 0402LF  page 267 : A = PVCCIN_CPU0_VOS2 ; B = PVCCIN_CPU0
R415  Q_RES  4.7K 1% CHIP  pkg 0402LF  page 153 : A = OCP_SFF_ID1 ; B = GND

(kicad_pcb
	(version 20260206)
	(generator "pcbnew")
	(generator_version "10.0")
	(general
		(thickness 1.6)
		(legacy_teardrops no)
	)
	(paper "A4")
	(title_block
		(title "03242023_DA0F0TMBIJ0_F0T_Motherboard_J_brd_V01_OCP.brd")
		(comment 1 "Grand Teton / footprints 5456-5457 of 6105")
	)
	(layers
		(0 "F.Cu" signal "TOP")
		(4 "In1.Cu" signal "GND")
		(6 "In2.Cu" signal "IN1")
		(8 "In3.Cu" signal "GND1")
		(10 "In4.Cu" signal "IN2")
		(12 "In5.Cu" signal "GND2")
		(14 "In6.Cu" signal "IN3")
		(16 "In7.Cu" signal "GND3")
		(18 "In8.Cu" signal "VCC")
		(20 "In9.Cu" signal "VCC1")
		(22 "In10.Cu" signal "GND4")
		(24 "In11.Cu" signal "IN4")
		(26 "In12.Cu" signal "GND5")
		(28 "In13.Cu" signal "IN5")
		(30 "In14.Cu" signal "GND6")
		(32 "In15.Cu" signal "IN6")
		(34 "In16.Cu" signal "GND7")
		(2 "B.Cu" signal "BOTTOM")
		(9 "F.Adhes" user "F.Adhesive")
		(11 "B.Adhes" user "B.Adhesive")
		(13 "F.Paste" user "Package Geometry/Pastemask Top")
		(15 "B.Paste" user "Package Geometry/Pastemask Bottom")
		(5 "F.SilkS" user "Ref Des/Silkscreen Top")
		(7 "B.SilkS" user "Ref Des/Silkscreen Bottom")
		(1 "F.Mask" user "Board Geometry/Soldermask Top")
		(3 "B.Mask" user "Board Geometry/Soldermask Bottom")
		(17 "Dwgs.User" user "User.Drawings")
		(19 "Cmts.User" user "User.Comments")
		(21 "Eco1.User" user "User.Eco1")
		(23 "Eco2.User" user "User.Eco2")
		(25 "Edge.Cuts" user "Board Geometry/Outline")
		(27 "Margin" user)
		(31 "F.CrtYd" user "Package Geometry/Place Bound Top")
		(29 "B.CrtYd" user "Package Geometry/Place Bound Bottom")
		(35 "F.Fab" user "Ref Des/Assembly Top")
		(33 "B.Fab" user "Ref Des/Assembly Bottom")
	)
	(footprint ""
		(layer "B.Cu")
		(at 350.158812 -337.853782)
		(property "Reference" "PR154"
			(at 0 0 0)
			(layer "B.SilkS")
			(hide yes)
			(effects
				(font
					(size 1.27 1.27)
				)
				(justify mirror)
			)
		)
		(property "Value" ""
			(at 0 0 0)
			(layer "B.Fab")
			(effects
				(font
					(size 1.27 1.27)
				)
				(justify mirror)
			)
		)
		(duplicate_pad_numbers_are_jumpers no)
		(fp_line
			(start -0.7874 -0.4064)
			(end -0.7874 0.4064)
			(stroke
				(width 0.1524)
				(type default)
			)
			(layer "B.SilkS")
		)
		(fp_line
			(start -0.7874 0.4064)
			(end 0.7874 0.4064)
			(stroke
				(width 0.1524)
				(type default)
			)
			(layer "B.SilkS")
		)
		(fp_line
			(start 0.7874 -0.4064)
			(end -0.7874 -0.4064)
			(stroke
				(width 0.1524)
				(type default)
			)
			(layer "B.SilkS")
		)
		(fp_line
			(start 0.7874 0.4064)
			(end 0.7874 -0.4064)
			(stroke
				(width 0.1524)
				(type default)
			)
			(layer "B.SilkS")
		)
		(fp_line
			(start -0.67945 -0.3048)
			(end -0.67945 0.3048)
			(stroke
				(width 0.1)
				(type default)
			)
			(layer "B.Fab")
		)
		(fp_line
			(start -0.67945 0.3048)
			(end -0.120396 0.3048)
			(stroke
				(width 0.1)
				(type default)
			)
			(layer "B.Fab")
		)
		(fp_line
			(start -0.12065 -0.3048)
			(end -0.67945 -0.3048)
			(stroke
				(width 0.1)
				(type default)
			)
			(layer "B.Fab")
		)
		(fp_line
			(start -0.12065 -0.2794)
			(end -0.12065 -0.3048)
			(stroke
				(width 0.1)
				(type default)
			)
			(layer "B.Fab")
		)
		(fp_line
			(start -0.120396 0.2794)
			(end 0.12065 0.2794)
			(stroke
				(width 0.1)
				(type default)
			)
			(layer "B.Fab")
		)
		(fp_line
			(start -0.120396 0.3048)
			(end -0.120396 0.2794)
			(stroke
				(width 0.1)
				(type default)
			)
			(layer "B.Fab")
		)
		(fp_line
			(start 0.12065 -0.305054)
			(end 0.12065 -0.2794)
			(stroke
				(width 0.1)
				(type default)
			)
			(layer "B.Fab")
		)
		(fp_line
			(start 0.12065 -0.2794)
			(end -0.12065 -0.2794)
			(stroke
				(width 0.1)
				(type default)
			)
			(layer "B.Fab")
		)
		(fp_line
			(start 0.12065 0.2794)
			(end 0.12065 0.3048)
			(stroke
				(width 0.1)
				(type default)
			)
			(layer "B.Fab")
		)
		(fp_line
			(start 0.12065 0.3048)
			(end 0.67945 0.3048)
			(stroke
				(width 0.1)
				(type default)
			)
			(layer "B.Fab")
		)
		(fp_line
			(start 0.67945 -0.305054)
			(end 0.12065 -0.305054)
			(stroke
				(width 0.1)
				(type default)
			)
			(layer "B.Fab")
		)
		(fp_line
			(start 0.67945 0.3048)
			(end 0.67945 -0.305054)
			(stroke
				(width 0.1)
				(type default)
			)
			(layer "B.Fab")
		)
		(pad "1" smd circle
			(at 0.40005 0 180)
			(size 0 0)
			(layers "B.Cu" "B.Mask" "B.Paste")
			(net "PVCCIN_CPU0_VOS2")
		)
		(pad "2" smd circle
			(at -0.40005 0 180)
			(size 0 0)
			(layers "B.Cu" "B.Mask" "B.Paste")
			(net "PVCCIN_CPU0")
		)
	)
	(footprint ""
		(layer "B.Cu")
		(at 449.526914 -8.344916 -90)
		(property "Reference" "R415"
			(at 0 0 90)
			(layer "B.SilkS")
			(hide yes)
			(effects
				(font
					(size 1.27 1.27)
				)
				(justify mirror)
			)
		)
		(property "Value" ""
			(at 0 0 90)
			(layer "B.Fab")
			(effects
				(font
					(size 1.27 1.27)
				)
				(justify mirror)
			)
		)
		(duplicate_pad_numbers_are_jumpers no)
		(fp_line
			(start -0.7874 0.4064)
			(end 0.7874 0.4064)
			(stroke
				(width 0.1524)
				(type default)
			)
			(layer "B.SilkS")
		)
		(fp_line
			(start 0.7874 0.4064)
			(end 0.7874 -0.4064)
			(stroke
				(width 0.1524)
				(type default)
			)
			(layer "B.SilkS")
		)
		(fp_line
			(start -0.7874 -0.4064)
			(end -0.7874 0.4064)
			(stroke
				(width 0.1524)
				(type default)
			)
			(layer "B.SilkS")
		)
		(fp_line
			(start 0.7874 -0.4064)
			(end -0.7874 -0.4064)
			(stroke
				(width 0.1524)
				(type default)
			)
			(layer "B.SilkS")
		)
		(fp_line
			(start -0.67945 0.3048)
			(end -0.120396 0.3048)
			(stroke
				(width 0.1)
				(type default)
			)
			(layer "B.Fab")
		)
		(fp_line
			(start -0.120396 0.3048)
			(end -0.120396 0.2794)
			(stroke
				(width 0.1)
				(type default)
			)
			(layer "B.Fab")
		)
		(fp_line
			(start 0.12065 0.3048)
			(end 0.67945 0.3048)
			(stroke
				(width 0.1)
				(type default)
			)
			(layer "B.Fab")
		)
		(fp_line
			(start 0.67945 0.3048)
			(end 0.67945 -0.305054)
			(stroke
				(width 0.1)
				(type default)
			)
			(layer "B.Fab")
		)
		(fp_line
			(start -0.120396 0.2794)
			(end 0.12065 0.2794)
			(stroke
				(width 0.1)
				(type default)
			)
			(layer "B.Fab")
		)
		(fp_line
			(start 0.12065 0.2794)
			(end 0.12065 0.3048)
			(stroke
				(width 0.1)
				(type default)
			)
			(layer "B.Fab")
		)
		(fp_line
			(start -0.12065 -0.2794)
			(end -0.12065 -0.3048)
			(stroke
				(width 0.1)
				(type default)
			)
			(layer "B.Fab")
		)
		(fp_line
			(start 0.12065 -0.2794)
			(end -0.12065 -0.2794)
			(stroke
				(width 0.1)
				(type default)
			)
			(layer "B.Fab")
		)
		(fp_line
			(start -0.67945 -0.3048)
			(end -0.67945 0.3048)
			(stroke
				(width 0.1)
				(type default)
			)
			(layer "B.Fab")
		)
		(fp_line
			(start -0.12065 -0.3048)
			(end -0.67945 -0.3048)
			(stroke
				(width 0.1)
				(type default)
			)
			(layer "B.Fab")
		)
		(fp_line
			(start 0.12065 -0.305054)
			(end 0.12065 -0.2794)
			(stroke
				(width 0.1)
				(type default)
			)
			(layer "B.Fab")
		)
		(fp_line
			(start 0.67945 -0.305054)
			(end 0.12065 -0.305054)
			(stroke
				(width 0.1)
				(type default)
			)
			(layer "B.Fab")
		)
		(pad "1" smd circle
			(at 0.40005 0 90)
			(size 0 0)
			(layers "B.Cu" "B.Mask" "B.Paste")
			(net "OCP_SFF_ID1")
		)
		(pad "2" smd circle
			(at -0.40005 0 90)
			(size 0 0)
			(layers "B.Cu" "B.Mask" "B.Paste")
			(net "GND")
		)
	)
)
